(kicad_pcb
	(version 20241229)
	(generator "pcbnew")
	(generator_version "9.0")
	(general
		(thickness 1.294)
		(legacy_teardrops no)
	)
	(paper "A3")
	(title_block
		(title "Kintex 410T devboard")
		(date "2024-04-03")
		(rev "1.1.2")
		(comment 9 "footprints 927-933 of 975")
	)
	(layers
		(0 "F.Cu" mixed)
		(4 "In1.Cu" power)
		(6 "In2.Cu" power)
		(8 "In3.Cu" mixed)
		(10 "In4.Cu" power)
		(12 "In5.Cu" mixed)
		(14 "In6.Cu" power)
		(16 "In7.Cu" mixed)
		(18 "In8.Cu" power)
		(2 "B.Cu" mixed)
		(9 "F.Adhes" user "F.Adhesive")
		(11 "B.Adhes" user "B.Adhesive")
		(13 "F.Paste" user)
		(15 "B.Paste" user)
		(5 "F.SilkS" user "F.Silkscreen")
		(7 "B.SilkS" user "B.Silkscreen")
		(1 "F.Mask" user)
		(3 "B.Mask" user)
		(17 "Dwgs.User" user "User.Drawings")
		(19 "Cmts.User" user "User.Comments")
		(21 "Eco1.User" user "User.Eco1")
		(23 "Eco2.User" user "User.Eco2")
		(25 "Edge.Cuts" user)
		(27 "Margin" user)
		(31 "F.CrtYd" user "F.Courtyard")
		(29 "B.CrtYd" user "B.Courtyard")
		(35 "F.Fab" user)
		(33 "B.Fab" user)
	)
	(footprint "antmicro-footprints:C_0402_1005Metric"
		(layer "B.Cu")
		(at 191.75 130.3)
		(descr "Capacitor SMD 0402")
		(tags "capacitor SMD 0402")
		(property "Reference" "C118"
			(at 22.925 -28.05 180)
			(layer "B.SilkS")
			(effects
				(font
					(size 0.7 0.7)
					(thickness 0.15)
				)
				(justify left bottom mirror)
			)
		)
		(property "Value" "C_100n_0402"
			(at 0 -1.169 180)
			(layer "B.Fab")
			(effects
				(font
					(size 0.7 0.7)
					(thickness 0.15)
				)
				(justify left bottom mirror)
			)
		)
		(property "Description" "SMD Multilayer Ceramic Capacitor, 0.1 µF, 50 V, 0402 [1005 Metric], ± 10%, X5R, GRM Series"
			(at 0 0 0)
			(layer "F.Fab")
			(hide yes)
			(effects
				(font
					(size 1.27 1.27)
					(thickness 0.15)
				)
			)
		)
		(property "Author" "Antmicro"
			(at 0 0 0)
			(layer "B.Fab")
			(hide yes)
			(effects
				(font
					(size 1 1)
					(thickness 0.15)
				)
				(justify mirror)
			)
		)
		(property "Dielectric" "X5R"
			(at 0 0 0)
			(layer "B.Fab")
			(hide yes)
			(effects
				(font
					(size 1 1)
					(thickness 0.15)
				)
				(justify mirror)
			)
		)
		(property "License" "Apache-2.0"
			(at 0 0 0)
			(layer "B.Fab")
			(hide yes)
			(effects
				(font
					(size 1 1)
					(thickness 0.15)
				)
				(justify mirror)
			)
		)
		(property "MPN" "GRM155R61H104KE14D"
			(at 0 0 0)
			(layer "B.Fab")
			(hide yes)
			(effects
				(font
					(size 1 1)
					(thickness 0.15)
				)
				(justify mirror)
			)
		)
		(property "Manufacturer" "Murata"
			(at 0 0 0)
			(layer "B.Fab")
			(hide yes)
			(effects
				(font
					(size 1 1)
					(thickness 0.15)
				)
				(justify mirror)
			)
		)
		(property "Val" "100n"
			(at 0 0 0)
			(layer "B.Fab")
			(hide yes)
			(effects
				(font
					(size 1 1)
					(thickness 0.15)
				)
				(justify mirror)
			)
		)
		(property "Voltage" "50V"
			(at 0 0 0)
			(layer "B.Fab")
			(hide yes)
			(effects
				(font
					(size 1 1)
					(thickness 0.15)
				)
				(justify mirror)
			)
		)
		(sheetname "FPGA supply")
		(sheetfile "fpga-supply.kicad_sch")
		(attr smd)
		(fp_rect
			(start -0.925 0.47)
			(end 0.925 -0.47)
			(stroke
				(width 0.05)
				(type default)
			)
			(fill no)
			(layer "B.CrtYd")
		)
		(fp_line
			(start -0.494 -0.248)
			(end -0.494 0.25)
			(stroke
				(width 0.15)
				(type solid)
			)
			(layer "B.Fab")
		)
		(fp_line
			(start -0.494 0.25)
			(end 0.504 0.25)
			(stroke
				(width 0.15)
				(type solid)
			)
			(layer "B.Fab")
		)
		(fp_line
			(start 0.504 -0.248)
			(end -0.494 -0.248)
			(stroke
				(width 0.15)
				(type solid)
			)
			(layer "B.Fab")
		)
		(fp_line
			(start 0.504 0.25)
			(end 0.504 -0.248)
			(stroke
				(width 0.15)
				(type solid)
			)
			(layer "B.Fab")
		)
		(pad "1" smd roundrect
			(at -0.48 0)
			(size 0.59 0.64)
			(layers "B.Cu" "B.Mask" "B.Paste")
			(roundrect_rratio 0.25)
			(net 26 "+1V8")
			(pintype "passive")
		)
		(pad "2" smd roundrect
			(at 0.48 0)
			(size 0.59 0.64)
			(layers "B.Cu" "B.Mask" "B.Paste")
			(roundrect_rratio 0.25)
			(net 1 "GND")
			(pintype "passive")
		)
	)
	(footprint "antmicro-footprints:R_0402_1005Metric"
		(layer "B.Cu")
		(at 189.36 79.8 90)
		(descr "Resistor SMD 0402")
		(tags "resistor SMD 0402")
		(property "Reference" "R144"
			(at -0.725 0.4 270)
			(layer "B.SilkS")
			(effects
				(font
					(size 0.7 0.7)
					(thickness 0.15)
				)
				(justify left bottom mirror)
			)
		)
		(property "Value" "R_100R_0402"
			(at 0 -1.4 270)
			(layer "B.Fab")
			(effects
				(font
					(size 0.7 0.7)
					(thickness 0.15)
				)
				(justify left bottom mirror)
			)
		)
		(property "Description" "SMD Chip Resistor, 100 ohm, ± 1%, 62.5 mW, 0402 [1005 Metric], Thick Film, General Purpose"
			(at 0 0 90)
			(layer "F.Fab")
			(hide yes)
			(effects
				(font
					(size 1.27 1.27)
					(thickness 0.15)
				)
			)
		)
		(property "Author" "Antmicro"
			(at 269.16 -109.56 0)
			(layer "B.Fab")
			(hide yes)
			(effects
				(font
					(size 1 1)
					(thickness 0.15)
				)
				(justify mirror)
			)
		)
		(property "License" "Apache-2.0"
			(at 269.16 -109.56 0)
			(layer "B.Fab")
			(hide yes)
			(effects
				(font
					(size 1 1)
					(thickness 0.15)
				)
				(justify mirror)
			)
		)
		(property "MPN" "CR0402-FX-1000GLF"
			(at 269.16 -109.56 0)
			(layer "B.Fab")
			(hide yes)
			(effects
				(font
					(size 1 1)
					(thickness 0.15)
				)
				(justify mirror)
			)
		)
		(property "Manufacturer" "Bourns"
			(at 269.16 -109.56 0)
			(layer "B.Fab")
			(hide yes)
			(effects
				(font
					(size 1 1)
					(thickness 0.15)
				)
				(justify mirror)
			)
		)
		(property "Tolerance" "1%"
			(at 269.16 -109.56 0)
			(layer "B.Fab")
			(hide yes)
			(effects
				(font
					(size 1 1)
					(thickness 0.15)
				)
				(justify mirror)
			)
		)
		(property "Val" "100R"
			(at 269.16 -109.56 0)
			(layer "B.Fab")
			(hide yes)
			(effects
				(font
					(size 1 1)
					(thickness 0.15)
				)
				(justify mirror)
			)
		)
		(sheetname "User GPIO + LED + button + DIP switch")
		(sheetfile "user-gpio.kicad_sch")
		(attr smd)
		(fp_rect
			(start -0.925 0.47)
			(end 0.925 -0.47)
			(stroke
				(width 0.05)
				(type default)
			)
			(fill no)
			(layer "B.CrtYd")
		)
		(fp_rect
			(start -0.5 0.25)
			(end 0.5 -0.25)
			(stroke
				(width 0.15)
				(type solid)
			)
			(fill no)
			(layer "B.Fab")
		)
		(pad "1" smd roundrect
			(at -0.48 0 90)
			(size 0.59 0.64)
			(layers "B.Cu" "B.Mask" "B.Paste")
			(roundrect_rratio 0.25)
			(net 489 "/FPGA Bank 12 & 13/CW_HEADER.IO1")
			(pintype "passive")
		)
		(pad "2" smd roundrect
			(at 0.48 0 90)
			(size 0.59 0.64)
			(layers "B.Cu" "B.Mask" "B.Paste")
			(roundrect_rratio 0.25)
			(net 827 "/User GPIO + LED + button + DIP switch/CW_20PIN_IO1")
			(pintype "passive")
		)
	)
	(footprint "antmicro-footprints:C_0201"
		(layer "B.Cu")
		(at 201.5 128.05)
		(descr "Capacitor SMD 0201")
		(tags "capacitor SMD 0201")
		(property "Reference" "C132"
			(at 24.375 -29.15 0)
			(layer "B.SilkS")
			(effects
				(font
					(size 0.7 0.7)
					(thickness 0.15)
				)
				(justify right bottom mirror)
			)
		)
		(property "Value" "C_100n_0201"
			(at 0 -1.4 0)
			(layer "B.Fab")
			(effects
				(font
					(size 0.7 0.7)
					(thickness 0.15)
				)
				(justify right bottom mirror)
			)
		)
		(property "Description" "SMD Multilayer Ceramic Capacitor, 0.1 µF, 6.3 V, 0201 [0603 Metric], ± 10%, X6S, CC Series"
			(at 0 0 0)
			(layer "F.Fab")
			(hide yes)
			(effects
				(font
					(size 1.27 1.27)
					(thickness 0.15)
				)
			)
		)
		(property "Author" "Antmicro"
			(at 0 0 0)
			(layer "B.Fab")
			(hide yes)
			(effects
				(font
					(size 1 1)
					(thickness 0.15)
				)
				(justify mirror)
			)
		)
		(property "Dielectric" ""
			(at 0 0 0)
			(layer "B.Fab")
			(hide yes)
			(effects
				(font
					(size 1 1)
					(thickness 0.15)
				)
				(justify mirror)
			)
		)
		(property "License" "Apache-2.0"
			(at 0 0 0)
			(layer "B.Fab")
			(hide yes)
			(effects
				(font
					(size 1 1)
					(thickness 0.15)
				)
				(justify mirror)
			)
		)
		(property "MPN" "CC0201KRX6S5BB104"
			(at 0 0 0)
			(layer "B.Fab")
			(hide yes)
			(effects
				(font
					(size 1 1)
					(thickness 0.15)
				)
				(justify mirror)
			)
		)
		(property "Manufacturer" "YAGEO"
			(at 0 0 0)
			(layer "B.Fab")
			(hide yes)
			(effects
				(font
					(size 1 1)
					(thickness 0.15)
				)
				(justify mirror)
			)
		)
		(property "Val" "100n"
			(at 0 0 0)
			(layer "B.Fab")
			(hide yes)
			(effects
				(font
					(size 1 1)
					(thickness 0.15)
				)
				(justify mirror)
			)
		)
		(property "Voltage" ""
			(at 0 0 0)
			(layer "B.Fab")
			(hide yes)
			(effects
				(font
					(size 1 1)
					(thickness 0.15)
				)
				(justify mirror)
			)
		)
		(sheetname "FPGA supply")
		(sheetfile "fpga-supply.kicad_sch")
		(attr smd)
		(fp_rect
			(start -0.7 0.35)
			(end 0.7 -0.35)
			(stroke
				(width 0.05)
				(type default)
			)
			(fill no)
			(layer "B.CrtYd")
		)
		(fp_rect
			(start 0.3 -0.15)
			(end -0.301 0.149)
			(stroke
				(width 0.15)
				(type solid)
			)
			(fill no)
			(layer "B.Fab")
		)
		(pad "" smd roundrect
			(at -0.349 0.002)
			(size 0.318 0.36)
			(layers "B.Paste")
			(roundrect_rratio 0.25)
		)
		(pad "" smd roundrect
			(at 0.341 0.002)
			(size 0.318 0.36)
			(layers "B.Paste")
			(roundrect_rratio 0.25)
		)
		(pad "1" smd roundrect
			(at -0.321 0.002)
			(size 0.46 0.4)
			(layers "B.Cu" "B.Mask")
			(roundrect_rratio 0.25)
			(net 1 "GND")
			(pintype "passive")
		)
		(pad "2" smd roundrect
			(at 0.32 0.002)
			(size 0.46 0.4)
			(layers "B.Cu" "B.Mask")
			(roundrect_rratio 0.25)
			(net 650 "+1V0")
			(pintype "passive")
		)
	)
	(footprint "antmicro-footprints:R_0402_1005Metric"
		(layer "B.Cu")
		(at 153.065 140.95 180)
		(descr "Resistor SMD 0402")
		(tags "resistor SMD 0402")
		(property "Reference" "R325"
			(at -1.31 0.525 0)
			(layer "B.SilkS")
			(effects
				(font
					(size 0.7 0.7)
					(thickness 0.15)
				)
				(justify left bottom mirror)
			)
		)
		(property "Value" "R_4k7_0402"
			(at 0 -1.4 0)
			(layer "B.Fab")
			(effects
				(font
					(size 0.7 0.7)
					(thickness 0.15)
				)
				(justify left bottom mirror)
			)
		)
		(property "Description" "SMD Chip Resistor, 4.7 kohm, ± 1%, 62.5 mW, 0402 [1005 Metric], Thick Film, General Purpose"
			(at 0 0 180)
			(layer "F.Fab")
			(hide yes)
			(effects
				(font
					(size 1.27 1.27)
					(thickness 0.15)
				)
			)
		)
		(property "Author" "Antmicro"
			(at 306.13 281.9 0)
			(layer "B.Fab")
			(hide yes)
			(effects
				(font
					(size 1 1)
					(thickness 0.15)
				)
				(justify mirror)
			)
		)
		(property "License" "Apache-2.0"
			(at 306.13 281.9 0)
			(layer "B.Fab")
			(hide yes)
			(effects
				(font
					(size 1 1)
					(thickness 0.15)
				)
				(justify mirror)
			)
		)
		(property "MPN" "CR0402-FX-4701GLF"
			(at 306.13 281.9 0)
			(layer "B.Fab")
			(hide yes)
			(effects
				(font
					(size 1 1)
					(thickness 0.15)
				)
				(justify mirror)
			)
		)
		(property "Manufacturer" "Bourns"
			(at 306.13 281.9 0)
			(layer "B.Fab")
			(hide yes)
			(effects
				(font
					(size 1 1)
					(thickness 0.15)
				)
				(justify mirror)
			)
		)
		(property "Tolerance" "1%"
			(at 306.13 281.9 0)
			(layer "B.Fab")
			(hide yes)
			(effects
				(font
					(size 1 1)
					(thickness 0.15)
				)
				(justify mirror)
			)
		)
		(property "Val" "4k7"
			(at 306.13 281.9 0)
			(layer "B.Fab")
			(hide yes)
			(effects
				(font
					(size 1 1)
					(thickness 0.15)
				)
				(justify mirror)
			)
		)
		(sheetname "DC-DC Converters")
		(sheetfile "dc-dc.kicad_sch")
		(attr smd)
		(fp_rect
			(start -0.925 0.47)
			(end 0.925 -0.47)
			(stroke
				(width 0.05)
				(type default)
			)
			(fill no)
			(layer "B.CrtYd")
		)
		(fp_rect
			(start -0.5 0.25)
			(end 0.5 -0.25)
			(stroke
				(width 0.15)
				(type solid)
			)
			(fill no)
			(layer "B.Fab")
		)
		(pad "1" smd roundrect
			(at -0.48 0 180)
			(size 0.59 0.64)
			(layers "B.Cu" "B.Mask" "B.Paste")
			(roundrect_rratio 0.25)
			(net 1 "GND")
			(pintype "passive")
		)
		(pad "2" smd roundrect
			(at 0.48 0 180)
			(size 0.59 0.64)
			(layers "B.Cu" "B.Mask" "B.Paste")
			(roundrect_rratio 0.25)
			(net 969 "/DC-DC Converters/MGTAVTT_ILIM")
			(pintype "passive")
		)
	)
	(footprint "antmicro-footprints:NetTie-2_SMD_Pad0.127mm"
		(layer "B.Cu")
		(at 208.860001 147.257 -90)
		(descr "Net tie, 2 pin, 0.127mm  SMD pads")
		(tags "net tie")
		(property "Reference" "NT30"
			(at -0.128 1.345 90)
			(layer "B.SilkS")
			(hide yes)
			(effects
				(font
					(size 0.7 0.7)
					(thickness 0.15)
				)
				(justify left bottom mirror)
			)
		)
		(property "Value" "Net-Tie_2"
			(at 0 -1.199 90)
			(layer "B.Fab")
			(effects
				(font
					(size 0.7 0.7)
					(thickness 0.15)
				)
				(justify left bottom mirror)
			)
		)
		(property "Description" "Net tie, 2 pins"
			(at 0 0 270)
			(layer "F.Fab")
			(hide yes)
			(effects
				(font
					(size 1.27 1.27)
					(thickness 0.15)
				)
			)
		)
		(property "Author" "Antmicro"
			(at 61.603001 356.117001 0)
			(layer "B.Fab")
			(hide yes)
			(effects
				(font
					(size 1 1)
					(thickness 0.15)
				)
				(justify mirror)
			)
		)
		(property "License" "Apache-2.0"
			(at 61.603001 356.117001 0)
			(layer "B.Fab")
			(hide yes)
			(effects
				(font
					(size 1 1)
					(thickness 0.15)
				)
				(justify mirror)
			)
		)
		(property "MPN" ""
			(at 61.603001 356.117001 0)
			(layer "B.Fab")
			(hide yes)
			(effects
				(font
					(size 1 1)
					(thickness 0.15)
				)
				(justify mirror)
			)
		)
		(property "Manufacturer" ""
			(at 61.603001 356.117001 0)
			(layer "B.Fab")
			(hide yes)
			(effects
				(font
					(size 1 1)
					(thickness 0.15)
				)
				(justify mirror)
			)
		)
		(sheetname "DC-DC Converters")
		(sheetfile "dc-dc.kicad_sch")
		(attr exclude_from_pos_files)
		(net_tie_pad_groups "1, 2")
		(fp_poly
			(pts
				(xy -0.0635 0.0635) (xy 0.0625 0.0635) (xy 0.0625 -0.0635) (xy -0.0635 -0.0635)
			)
			(stroke
				(width 0)
				(type solid)
			)
			(fill yes)
			(layer "B.Cu")
		)
		(pad "1" smd roundrect
			(at -0.127 0 90)
			(size 0.127 0.127)
			(layers "B.Cu")
			(roundrect_rratio 0.5)
			(chamfer_ratio 0)
			(chamfer top_left bottom_left)
			(net 1 "GND")
			(pinfunction "1")
			(pintype "passive")
		)
		(pad "2" smd roundrect
			(at 0.126 0 270)
			(size 0.127 0.127)
			(layers "B.Cu")
			(roundrect_rratio 0.5)
			(chamfer_ratio 0)
			(chamfer top_left bottom_left)
			(net 1218 "/DC-DC Converters/SENSE_3V3_2_N")
			(pinfunction "2")
			(pintype "passive")
		)
	)
	(footprint "antmicro-footprints:R_0402_1005Metric"
		(layer "B.Cu")
		(at 202.2 90.8 90)
		(descr "Resistor SMD 0402")
		(tags "resistor SMD 0402")
		(property "Reference" "R205"
			(at 1.95 2.4 270)
			(layer "B.SilkS")
			(effects
				(font
					(size 0.7 0.7)
					(thickness 0.15)
				)
				(justify left bottom mirror)
			)
		)
		(property "Value" "R_10k_0402"
			(at 0 -1.4 270)
			(layer "B.Fab")
			(effects
				(font
					(size 0.7 0.7)
					(thickness 0.15)
				)
				(justify left bottom mirror)
			)
		)
		(property "Description" "SMD Chip Resistor, 10 kohm, ± 1%, 62.5 mW, 0402 [1005 Metric], Thick Film, General Purpose"
			(at 0 0 90)
			(layer "F.Fab")
			(hide yes)
			(effects
				(font
					(size 1.27 1.27)
					(thickness 0.15)
				)
			)
		)
		(property "Author" "Antmicro"
			(at 293 -111.4 0)
			(layer "B.Fab")
			(hide yes)
			(effects
				(font
					(size 1 1)
					(thickness 0.15)
				)
				(justify mirror)
			)
		)
		(property "License" "Apache-2.0"
			(at 293 -111.4 0)
			(layer "B.Fab")
			(hide yes)
			(effects
				(font
					(size 1 1)
					(thickness 0.15)
				)
				(justify mirror)
			)
		)
		(property "MPN" "CR0402-FX-1002GLF"
			(at 293 -111.4 0)
			(layer "B.Fab")
			(hide yes)
			(effects
				(font
					(size 1 1)
					(thickness 0.15)
				)
				(justify mirror)
			)
		)
		(property "Manufacturer" "Bourns"
			(at 293 -111.4 0)
			(layer "B.Fab")
			(hide yes)
			(effects
				(font
					(size 1 1)
					(thickness 0.15)
				)
				(justify mirror)
			)
		)
		(property "Tolerance" "1%"
			(at 293 -111.4 0)
			(layer "B.Fab")
			(hide yes)
			(effects
				(font
					(size 1 1)
					(thickness 0.15)
				)
				(justify mirror)
			)
		)
		(property "Val" "10k"
			(at 293 -111.4 0)
			(layer "B.Fab")
			(hide yes)
			(effects
				(font
					(size 1 1)
					(thickness 0.15)
				)
				(justify mirror)
			)
		)
		(sheetname "HDMI + Ethernet")
		(sheetfile "hdmi-ethernet.kicad_sch")
		(attr smd)
		(fp_rect
			(start -0.925 0.47)
			(end 0.925 -0.47)
			(stroke
				(width 0.05)
				(type default)
			)
			(fill no)
			(layer "B.CrtYd")
		)
		(fp_rect
			(start -0.5 0.25)
			(end 0.5 -0.25)
			(stroke
				(width 0.15)
				(type solid)
			)
			(fill no)
			(layer "B.Fab")
		)
		(pad "1" smd roundrect
			(at -0.48 0 90)
			(size 0.59 0.64)
			(layers "B.Cu" "B.Mask" "B.Paste")
			(roundrect_rratio 0.25)
			(net 851 "/HDMI + Ethernet/GBE_LED_LINK-")
			(pintype "passive")
		)
		(pad "2" smd roundrect
			(at 0.48 0 90)
			(size 0.59 0.64)
			(layers "B.Cu" "B.Mask" "B.Paste")
			(roundrect_rratio 0.25)
			(net 24 "+3V3")
			(pintype "passive")
		)
	)
	(footprint "antmicro-footprints:SOD-523"
		(layer "B.Cu")
		(at 249.401 114.2 180)
		(property "Reference" "D31"
			(at 1.076 -0.375 0)
			(layer "B.SilkS")
			(effects
				(font
					(size 0.7 0.7)
					(thickness 0.15)
				)
				(justify left bottom mirror)
			)
		)
		(property "Value" "BAT54-02V-G3-08"
			(at 0 -1.499 0)
			(layer "B.Fab")
			(effects
				(font
					(size 0.7 0.7)
					(thickness 0.15)
				)
				(justify left bottom mirror)
			)
		)
		(property "Description" "Small Signal Schottky Diode, Single, 30 V, 200 mA, 800 mV, 600 mA, 125 °C"
			(at 0 0 180)
			(layer "F.Fab")
			(hide yes)
			(effects
				(font
					(size 1.27 1.27)
					(thickness 0.15)
				)
			)
		)
		(property "Author" "Antmicro"
			(at 498.802 228.4 0)
			(layer "B.Fab")
			(hide yes)
			(effects
				(font
					(size 1 1)
					(thickness 0.15)
				)
				(justify mirror)
			)
		)
		(property "License" "Apache-2.0"
			(at 498.802 228.4 0)
			(layer "B.Fab")
			(hide yes)
			(effects
				(font
					(size 1 1)
					(thickness 0.15)
				)
				(justify mirror)
			)
		)
		(property "MPN" "BAT54-02V-G3-08"
			(at 498.802 228.4 0)
			(layer "B.Fab")
			(hide yes)
			(effects
				(font
					(size 1 1)
					(thickness 0.15)
				)
				(justify mirror)
			)
		)
		(property "Manufacturer" "Vishay"
			(at 498.802 228.4 0)
			(layer "B.Fab")
			(hide yes)
			(effects
				(font
					(size 1 1)
					(thickness 0.15)
				)
				(justify mirror)
			)
		)
		(property "Public" "False"
			(at 498.802 228.4 0)
			(layer "B.Fab")
			(hide yes)
			(effects
				(font
					(size 1 1)
					(thickness 0.15)
				)
				(justify mirror)
			)
		)
		(sheetname "HDMI + Ethernet")
		(sheetfile "hdmi-ethernet.kicad_sch")
		(attr smd)
		(fp_line
			(start -0.35 0.5)
			(end -0.35 -0.5)
			(stroke
				(width 0.15)
				(type solid)
			)
			(layer "B.SilkS")
		)
		(fp_rect
			(start -1 0.6)
			(end 1 -0.6)
			(stroke
				(width 0.05)
				(type solid)
			)
			(fill no)
			(layer "B.CrtYd")
		)
		(fp_line
			(start 0.65 0.425)
			(end 0.65 -0.423)
			(stroke
				(width 0.15)
				(type solid)
			)
			(layer "B.Fab")
		)
		(fp_line
			(start -0.35 0.4)
			(end -0.35 -0.4)
			(stroke
				(width 0.15)
				(type solid)
			)
			(layer "B.Fab")
		)
		(fp_line
			(start -0.652 0.425)
			(end 0.65 0.425)
			(stroke
				(width 0.15)
				(type solid)
			)
			(layer "B.Fab")
		)
		(fp_line
			(start -0.652 -0.423)
			(end 0.65 -0.423)
			(stroke
				(width 0.15)
				(type solid)
			)
			(layer "B.Fab")
		)
		(fp_line
			(start -0.652 -0.423)
			(end -0.652 0.425)
			(stroke
				(width 0.15)
				(type solid)
			)
			(layer "B.Fab")
		)
		(pad "1" smd roundrect
			(at -0.701 0 180)
			(size 0.5 0.6)
			(layers "B.Cu" "B.Mask" "B.Paste")
			(roundrect_rratio 0.25)
			(net 794 "/HDMI + Ethernet/HDMI_CONN_5V")
			(pinfunction "C")
			(pintype "passive")
		)
		(pad "2" smd roundrect
			(at 0.699 0 180)
			(size 0.5 0.6)
			(layers "B.Cu" "B.Mask" "B.Paste")
			(roundrect_rratio 0.25)
			(net 795 "/HDMI + Ethernet/HDMI_5V")
			(pinfunction "A")
			(pintype "passive")
		)
	)
)
